(kicad_pcb
	(version 20260206)
	(generator "pcbnew")
	(generator_version "10.0")
	(general
		(thickness 1.6)
		(legacy_teardrops no)
	)
	(paper "A4")
	(title_block
		(title "04192023_DAF0TMB3IC0_F0TG_MB_C_brd_V02_OCP.brd")
		(comment 1 "Grand Teton / footprints 1690-1695 of 8354")
	)
	(layers
		(0 "F.Cu" signal "TOP")
		(4 "In1.Cu" signal "GND")
		(6 "In2.Cu" signal "IN1")
		(8 "In3.Cu" signal "GND1")
		(10 "In4.Cu" signal "IN2")
		(12 "In5.Cu" signal "GND2")
		(14 "In6.Cu" signal "IN3")
		(16 "In7.Cu" signal "GND3")
		(18 "In8.Cu" signal "VCC")
		(20 "In9.Cu" signal "VCC1")
		(22 "In10.Cu" signal "GND4")
		(24 "In11.Cu" signal "IN4")
		(26 "In12.Cu" signal "GND5")
		(28 "In13.Cu" signal "IN5")
		(30 "In14.Cu" signal "GND6")
		(32 "In15.Cu" signal "IN6")
		(34 "In16.Cu" signal "GND7")
		(2 "B.Cu" signal "BOTTOM")
		(9 "F.Adhes" user "F.Adhesive")
		(11 "B.Adhes" user "B.Adhesive")
		(13 "F.Paste" user "Package Geometry/Pastemask Top")
		(15 "B.Paste" user "Package Geometry/Pastemask Bottom")
		(5 "F.SilkS" user "Ref Des/Silkscreen Top")
		(7 "B.SilkS" user "Ref Des/Silkscreen Bottom")
		(1 "F.Mask" user "Board Geometry/Soldermask Top")
		(3 "B.Mask" user "Board Geometry/Soldermask Bottom")
		(17 "Dwgs.User" user "User.Drawings")
		(19 "Cmts.User" user "User.Comments")
		(21 "Eco1.User" user "User.Eco1")
		(23 "Eco2.User" user "User.Eco2")
		(25 "Edge.Cuts" user "Board Geometry/Outline")
		(27 "Margin" user)
		(31 "F.CrtYd" user "Package Geometry/Place Bound Top")
		(29 "B.CrtYd" user "Package Geometry/Place Bound Bottom")
		(35 "F.Fab" user "Ref Des/Assembly Top")
		(33 "B.Fab" user "Ref Des/Assembly Bottom")
	)
	(footprint ""
		(layer "F.Cu")
		(at 194.217798 -398.940782 180)
		(property "Reference" "PC2347"
			(at 0 0 180)
			(layer "F.SilkS")
			(hide yes)
			(effects
				(font
					(size 1.27 1.27)
				)
			)
		)
		(property "Value" ""
			(at 0 0 180)
			(layer "F.Fab")
			(effects
				(font
					(size 1.27 1.27)
				)
			)
		)
		(duplicate_pad_numbers_are_jumpers no)
		(fp_line
			(start 0.7874 0.4064)
			(end -0.7874 0.4064)
			(stroke
				(width 0.1524)
				(type default)
			)
			(layer "F.SilkS")
		)
		(fp_line
			(start 0.7874 -0.4064)
			(end 0.7874 0.4064)
			(stroke
				(width 0.1524)
				(type default)
			)
			(layer "F.SilkS")
		)
		(fp_line
			(start -0.7874 0.4064)
			(end -0.7874 -0.4064)
			(stroke
				(width 0.1524)
				(type default)
			)
			(layer "F.SilkS")
		)
		(fp_line
			(start -0.7874 -0.4064)
			(end 0.7874 -0.4064)
			(stroke
				(width 0.1524)
				(type default)
			)
			(layer "F.SilkS")
		)
		(fp_line
			(start 0.67945 0.3048)
			(end 0.120396 0.3048)
			(stroke
				(width 0.1)
				(type default)
			)
			(layer "F.Fab")
		)
		(fp_line
			(start 0.67945 -0.3048)
			(end 0.67945 0.3048)
			(stroke
				(width 0.1)
				(type default)
			)
			(layer "F.Fab")
		)
		(fp_line
			(start 0.12065 -0.2794)
			(end 0.12065 -0.3048)
			(stroke
				(width 0.1)
				(type default)
			)
			(layer "F.Fab")
		)
		(fp_line
			(start 0.12065 -0.3048)
			(end 0.67945 -0.3048)
			(stroke
				(width 0.1)
				(type default)
			)
			(layer "F.Fab")
		)
		(fp_line
			(start 0.120396 0.3048)
			(end 0.120396 0.2794)
			(stroke
				(width 0.1)
				(type default)
			)
			(layer "F.Fab")
		)
		(fp_line
			(start 0.120396 0.2794)
			(end -0.12065 0.2794)
			(stroke
				(width 0.1)
				(type default)
			)
			(layer "F.Fab")
		)
		(fp_line
			(start -0.12065 0.3048)
			(end -0.67945 0.3048)
			(stroke
				(width 0.1)
				(type default)
			)
			(layer "F.Fab")
		)
		(fp_line
			(start -0.12065 0.2794)
			(end -0.12065 0.3048)
			(stroke
				(width 0.1)
				(type default)
			)
			(layer "F.Fab")
		)
		(fp_line
			(start -0.12065 -0.2794)
			(end 0.12065 -0.2794)
			(stroke
				(width 0.1)
				(type default)
			)
			(layer "F.Fab")
		)
		(fp_line
			(start -0.12065 -0.305054)
			(end -0.12065 -0.2794)
			(stroke
				(width 0.1)
				(type default)
			)
			(layer "F.Fab")
		)
		(fp_line
			(start -0.67945 0.3048)
			(end -0.67945 -0.305054)
			(stroke
				(width 0.1)
				(type default)
			)
			(layer "F.Fab")
		)
		(fp_line
			(start -0.67945 -0.305054)
			(end -0.12065 -0.305054)
			(stroke
				(width 0.1)
				(type default)
			)
			(layer "F.Fab")
		)
		(pad "1" smd circle
			(at -0.40005 0 180)
			(size 0 0)
			(layers "F.Cu" "F.Mask" "F.Paste")
			(net "HSC_OCREF")
		)
		(pad "2" smd circle
			(at 0.40005 0 180)
			(size 0 0)
			(layers "F.Cu" "F.Mask" "F.Paste")
			(net "AGND_HSC")
		)
	)
	(footprint ""
		(layer "F.Cu")
		(at 235.068872 -67.474338 -90)
		(property "Reference" "C508"
			(at 0 0 270)
			(layer "F.SilkS")
			(hide yes)
			(effects
				(font
					(size 1.27 1.27)
				)
			)
		)
		(property "Value" ""
			(at 0 0 270)
			(layer "F.Fab")
			(effects
				(font
					(size 1.27 1.27)
				)
			)
		)
		(duplicate_pad_numbers_are_jumpers no)
		(fp_line
			(start -0.7874 0.4064)
			(end -0.7874 -0.4064)
			(stroke
				(width 0.1524)
				(type default)
			)
			(layer "F.SilkS")
		)
		(fp_line
			(start 0.7874 0.4064)
			(end -0.7874 0.4064)
			(stroke
				(width 0.1524)
				(type default)
			)
			(layer "F.SilkS")
		)
		(fp_line
			(start -0.7874 -0.4064)
			(end 0.7874 -0.4064)
			(stroke
				(width 0.1524)
				(type default)
			)
			(layer "F.SilkS")
		)
		(fp_line
			(start 0.7874 -0.4064)
			(end 0.7874 0.4064)
			(stroke
				(width 0.1524)
				(type default)
			)
			(layer "F.SilkS")
		)
		(fp_line
			(start -0.67945 0.3048)
			(end -0.67945 -0.305054)
			(stroke
				(width 0.1)
				(type default)
			)
			(layer "F.Fab")
		)
		(fp_line
			(start -0.12065 0.3048)
			(end -0.67945 0.3048)
			(stroke
				(width 0.1)
				(type default)
			)
			(layer "F.Fab")
		)
		(fp_line
			(start 0.120396 0.3048)
			(end 0.120396 0.2794)
			(stroke
				(width 0.1)
				(type default)
			)
			(layer "F.Fab")
		)
		(fp_line
			(start 0.67945 0.3048)
			(end 0.120396 0.3048)
			(stroke
				(width 0.1)
				(type default)
			)
			(layer "F.Fab")
		)
		(fp_line
			(start -0.12065 0.2794)
			(end -0.12065 0.3048)
			(stroke
				(width 0.1)
				(type default)
			)
			(layer "F.Fab")
		)
		(fp_line
			(start 0.120396 0.2794)
			(end -0.12065 0.2794)
			(stroke
				(width 0.1)
				(type default)
			)
			(layer "F.Fab")
		)
		(fp_line
			(start -0.12065 -0.2794)
			(end 0.12065 -0.2794)
			(stroke
				(width 0.1)
				(type default)
			)
			(layer "F.Fab")
		)
		(fp_line
			(start 0.12065 -0.2794)
			(end 0.12065 -0.3048)
			(stroke
				(width 0.1)
				(type default)
			)
			(layer "F.Fab")
		)
		(fp_line
			(start 0.12065 -0.3048)
			(end 0.67945 -0.3048)
			(stroke
				(width 0.1)
				(type default)
			)
			(layer "F.Fab")
		)
		(fp_line
			(start 0.67945 -0.3048)
			(end 0.67945 0.3048)
			(stroke
				(width 0.1)
				(type default)
			)
			(layer "F.Fab")
		)
		(fp_line
			(start -0.67945 -0.305054)
			(end -0.12065 -0.305054)
			(stroke
				(width 0.1)
				(type default)
			)
			(layer "F.Fab")
		)
		(fp_line
			(start -0.12065 -0.305054)
			(end -0.12065 -0.2794)
			(stroke
				(width 0.1)
				(type default)
			)
			(layer "F.Fab")
		)
		(pad "1" smd circle
			(at -0.40005 0 270)
			(size 0 0)
			(layers "F.Cu" "F.Mask" "F.Paste")
			(net "P3V3_E1S_0")
		)
		(pad "2" smd circle
			(at 0.40005 0 270)
			(size 0 0)
			(layers "F.Cu" "F.Mask" "F.Paste")
			(net "GND")
		)
	)
	(footprint ""
		(layer "F.Cu")
		(at 357.284782 -412.030418)
		(property "Reference" "C15"
			(at 0 0 0)
			(layer "F.SilkS")
			(hide yes)
			(effects
				(font
					(size 1.27 1.27)
				)
			)
		)
		(property "Value" ""
			(at 0 0 0)
			(layer "F.Fab")
			(effects
				(font
					(size 1.27 1.27)
				)
			)
		)
		(duplicate_pad_numbers_are_jumpers no)
		(fp_line
			(start -0.7874 -0.4064)
			(end 0.7874 -0.4064)
			(stroke
				(width 0.1524)
				(type default)
			)
			(layer "F.SilkS")
		)
		(fp_line
			(start -0.7874 0.4064)
			(end -0.7874 -0.4064)
			(stroke
				(width 0.1524)
				(type default)
			)
			(layer "F.SilkS")
		)
		(fp_line
			(start 0.7874 -0.4064)
			(end 0.7874 0.4064)
			(stroke
				(width 0.1524)
				(type default)
			)
			(layer "F.SilkS")
		)
		(fp_line
			(start 0.7874 0.4064)
			(end -0.7874 0.4064)
			(stroke
				(width 0.1524)
				(type default)
			)
			(layer "F.SilkS")
		)
		(fp_line
			(start -0.67945 -0.305054)
			(end -0.12065 -0.305054)
			(stroke
				(width 0.1)
				(type default)
			)
			(layer "F.Fab")
		)
		(fp_line
			(start -0.67945 0.3048)
			(end -0.67945 -0.305054)
			(stroke
				(width 0.1)
				(type default)
			)
			(layer "F.Fab")
		)
		(fp_line
			(start -0.12065 -0.305054)
			(end -0.12065 -0.2794)
			(stroke
				(width 0.1)
				(type default)
			)
			(layer "F.Fab")
		)
		(fp_line
			(start -0.12065 -0.2794)
			(end 0.12065 -0.2794)
			(stroke
				(width 0.1)
				(type default)
			)
			(layer "F.Fab")
		)
		(fp_line
			(start -0.12065 0.2794)
			(end -0.12065 0.3048)
			(stroke
				(width 0.1)
				(type default)
			)
			(layer "F.Fab")
		)
		(fp_line
			(start -0.12065 0.3048)
			(end -0.67945 0.3048)
			(stroke
				(width 0.1)
				(type default)
			)
			(layer "F.Fab")
		)
		(fp_line
			(start 0.120396 0.2794)
			(end -0.12065 0.2794)
			(stroke
				(width 0.1)
				(type default)
			)
			(layer "F.Fab")
		)
		(fp_line
			(start 0.120396 0.3048)
			(end 0.120396 0.2794)
			(stroke
				(width 0.1)
				(type default)
			)
			(layer "F.Fab")
		)
		(fp_line
			(start 0.12065 -0.3048)
			(end 0.67945 -0.3048)
			(stroke
				(width 0.1)
				(type default)
			)
			(layer "F.Fab")
		)
		(fp_line
			(start 0.12065 -0.2794)
			(end 0.12065 -0.3048)
			(stroke
				(width 0.1)
				(type default)
			)
			(layer "F.Fab")
		)
		(fp_line
			(start 0.67945 -0.3048)
			(end 0.67945 0.3048)
			(stroke
				(width 0.1)
				(type default)
			)
			(layer "F.Fab")
		)
		(fp_line
			(start 0.67945 0.3048)
			(end 0.120396 0.3048)
			(stroke
				(width 0.1)
				(type default)
			)
			(layer "F.Fab")
		)
		(pad "1" smd circle
			(at -0.40005 0)
			(size 0 0)
			(layers "F.Cu" "F.Mask" "F.Paste")
			(net "PRSNT_CABLE_GPU_A1_ISO_N")
		)
		(pad "2" smd circle
			(at 0.40005 0)
			(size 0 0)
			(layers "F.Cu" "F.Mask" "F.Paste")
			(net "GND")
		)
	)
	(footprint ""
		(layer "F.Cu")
		(at 74.628502 -339.377274)
		(property "Reference" "PC376_2"
			(at 0 0 0)
			(layer "F.SilkS")
			(hide yes)
			(effects
				(font
					(size 1.27 1.27)
				)
			)
		)
		(property "Value" ""
			(at 0 0 0)
			(layer "F.Fab")
			(effects
				(font
					(size 1.27 1.27)
				)
			)
		)
		(duplicate_pad_numbers_are_jumpers no)
		(fp_line
			(start -0.7874 -0.4064)
			(end 0.7874 -0.4064)
			(stroke
				(width 0.1524)
				(type default)
			)
			(layer "F.SilkS")
		)
		(fp_line
			(start -0.7874 0.4064)
			(end -0.7874 -0.4064)
			(stroke
				(width 0.1524)
				(type default)
			)
			(layer "F.SilkS")
		)
		(fp_line
			(start 0.7874 -0.4064)
			(end 0.7874 0.4064)
			(stroke
				(width 0.1524)
				(type default)
			)
			(layer "F.SilkS")
		)
		(fp_line
			(start 0.7874 0.4064)
			(end -0.7874 0.4064)
			(stroke
				(width 0.1524)
				(type default)
			)
			(layer "F.SilkS")
		)
		(fp_line
			(start -0.67945 -0.305054)
			(end -0.12065 -0.305054)
			(stroke
				(width 0.1)
				(type default)
			)
			(layer "F.Fab")
		)
		(fp_line
			(start -0.67945 0.3048)
			(end -0.67945 -0.305054)
			(stroke
				(width 0.1)
				(type default)
			)
			(layer "F.Fab")
		)
		(fp_line
			(start -0.12065 -0.305054)
			(end -0.12065 -0.2794)
			(stroke
				(width 0.1)
				(type default)
			)
			(layer "F.Fab")
		)
		(fp_line
			(start -0.12065 -0.2794)
			(end 0.12065 -0.2794)
			(stroke
				(width 0.1)
				(type default)
			)
			(layer "F.Fab")
		)
		(fp_line
			(start -0.12065 0.2794)
			(end -0.12065 0.3048)
			(stroke
				(width 0.1)
				(type default)
			)
			(layer "F.Fab")
		)
		(fp_line
			(start -0.12065 0.3048)
			(end -0.67945 0.3048)
			(stroke
				(width 0.1)
				(type default)
			)
			(layer "F.Fab")
		)
		(fp_line
			(start 0.120396 0.2794)
			(end -0.12065 0.2794)
			(stroke
				(width 0.1)
				(type default)
			)
			(layer "F.Fab")
		)
		(fp_line
			(start 0.120396 0.3048)
			(end 0.120396 0.2794)
			(stroke
				(width 0.1)
				(type default)
			)
			(layer "F.Fab")
		)
		(fp_line
			(start 0.12065 -0.3048)
			(end 0.67945 -0.3048)
			(stroke
				(width 0.1)
				(type default)
			)
			(layer "F.Fab")
		)
		(fp_line
			(start 0.12065 -0.2794)
			(end 0.12065 -0.3048)
			(stroke
				(width 0.1)
				(type default)
			)
			(layer "F.Fab")
		)
		(fp_line
			(start 0.67945 -0.3048)
			(end 0.67945 0.3048)
			(stroke
				(width 0.1)
				(type default)
			)
			(layer "F.Fab")
		)
		(fp_line
			(start 0.67945 0.3048)
			(end 0.120396 0.3048)
			(stroke
				(width 0.1)
				(type default)
			)
			(layer "F.Fab")
		)
		(pad "1" smd circle
			(at -0.40005 0)
			(size 0 0)
			(layers "F.Cu" "F.Mask" "F.Paste")
			(net "SW_P12V_AUX_PVDDCR_CPU1_P1_FLT")
		)
		(pad "2" smd circle
			(at 0.40005 0)
			(size 0 0)
			(layers "F.Cu" "F.Mask" "F.Paste")
			(net "GND")
		)
	)
	(footprint ""
		(layer "F.Cu")
		(at 76.184252 -401.925536 90)
		(property "Reference" "C7039"
			(at 0 0 90)
			(layer "F.SilkS")
			(hide yes)
			(effects
				(font
					(size 1.27 1.27)
				)
			)
		)
		(property "Value" ""
			(at 0 0 90)
			(layer "F.Fab")
			(effects
				(font
					(size 1.27 1.27)
				)
			)
		)
		(duplicate_pad_numbers_are_jumpers no)
		(fp_line
			(start 1.524 -0.762)
			(end 1.524 0.762)
			(stroke
				(width 0.1524)
				(type default)
			)
			(layer "F.SilkS")
		)
		(fp_line
			(start -1.524 -0.762)
			(end 1.524 -0.762)
			(stroke
				(width 0.1524)
				(type default)
			)
			(layer "F.SilkS")
		)
		(fp_line
			(start 1.524 0.762)
			(end -1.524 0.762)
			(stroke
				(width 0.1524)
				(type default)
			)
			(layer "F.SilkS")
		)
		(fp_line
			(start -1.524 0.762)
			(end -1.524 -0.762)
			(stroke
				(width 0.1524)
				(type default)
			)
			(layer "F.SilkS")
		)
		(fp_line
			(start 1.1049 -0.724916)
			(end -1.1049 -0.724916)
			(stroke
				(width 0.1)
				(type default)
			)
			(layer "F.Fab")
		)
		(fp_line
			(start -1.1049 -0.724916)
			(end -1.1049 0.724916)
			(stroke
				(width 0.1)
				(type default)
			)
			(layer "F.Fab")
		)
		(fp_line
			(start 1.1049 0.724916)
			(end 1.1049 -0.724916)
			(stroke
				(width 0.1)
				(type default)
			)
			(layer "F.Fab")
		)
		(fp_line
			(start -1.1049 0.724916)
			(end 1.1049 0.724916)
			(stroke
				(width 0.1)
				(type default)
			)
			(layer "F.Fab")
		)
		(pad "1" smd rect
			(at -0.889 0 270)
			(size 1.016 1.27)
			(layers "F.Cu" "F.Mask" "F.Paste")
			(net "P0V9_CPU1_RT_2D")
		)
		(pad "2" smd rect
			(at 0.889 0 270)
			(size 1.016 1.27)
			(layers "F.Cu" "F.Mask" "F.Paste")
			(net "GND")
		)
	)
	(footprint ""
		(layer "F.Cu")
		(at 182.404766 -168.317418 -90)
		(property "Reference" "R5012"
			(at 0 0 270)
			(layer "F.SilkS")
			(hide yes)
			(effects
				(font
					(size 1.27 1.27)
				)
			)
		)
		(property "Value" ""
			(at 0 0 270)
			(layer "F.Fab")
			(effects
				(font
					(size 1.27 1.27)
				)
			)
		)
		(duplicate_pad_numbers_are_jumpers no)
		(fp_line
			(start -0.7874 0.4064)
			(end -0.7874 -0.4064)
			(stroke
				(width 0.1524)
				(type default)
			)
			(layer "F.SilkS")
		)
		(fp_line
			(start 0.7874 0.4064)
			(end -0.7874 0.4064)
			(stroke
				(width 0.1524)
				(type default)
			)
			(layer "F.SilkS")
		)
		(fp_line
			(start -0.7874 -0.4064)
			(end 0.7874 -0.4064)
			(stroke
				(width 0.1524)
				(type default)
			)
			(layer "F.SilkS")
		)
		(fp_line
			(start 0.7874 -0.4064)
			(end 0.7874 0.4064)
			(stroke
				(width 0.1524)
				(type default)
			)
			(layer "F.SilkS")
		)
		(fp_line
			(start -0.67945 0.3048)
			(end -0.67945 -0.305054)
			(stroke
				(width 0.1)
				(type default)
			)
			(layer "F.Fab")
		)
		(fp_line
			(start -0.12065 0.3048)
			(end -0.67945 0.3048)
			(stroke
				(width 0.1)
				(type default)
			)
			(layer "F.Fab")
		)
		(fp_line
			(start 0.120396 0.3048)
			(end 0.120396 0.2794)
			(stroke
				(width 0.1)
				(type default)
			)
			(layer "F.Fab")
		)
		(fp_line
			(start 0.67945 0.3048)
			(end 0.120396 0.3048)
			(stroke
				(width 0.1)
				(type default)
			)
			(layer "F.Fab")
		)
		(fp_line
			(start -0.12065 0.2794)
			(end -0.12065 0.3048)
			(stroke
				(width 0.1)
				(type default)
			)
			(layer "F.Fab")
		)
		(fp_line
			(start 0.120396 0.2794)
			(end -0.12065 0.2794)
			(stroke
				(width 0.1)
				(type default)
			)
			(layer "F.Fab")
		)
		(fp_line
			(start -0.12065 -0.2794)
			(end 0.12065 -0.2794)
			(stroke
				(width 0.1)
				(type default)
			)
			(layer "F.Fab")
		)
		(fp_line
			(start 0.12065 -0.2794)
			(end 0.12065 -0.3048)
			(stroke
				(width 0.1)
				(type default)
			)
			(layer "F.Fab")
		)
		(fp_line
			(start 0.12065 -0.3048)
			(end 0.67945 -0.3048)
			(stroke
				(width 0.1)
				(type default)
			)
			(layer "F.Fab")
		)
		(fp_line
			(start 0.67945 -0.3048)
			(end 0.67945 0.3048)
			(stroke
				(width 0.1)
				(type default)
			)
			(layer "F.Fab")
		)
		(fp_line
			(start -0.67945 -0.305054)
			(end -0.12065 -0.305054)
			(stroke
				(width 0.1)
				(type default)
			)
			(layer "F.Fab")
		)
		(fp_line
			(start -0.12065 -0.305054)
			(end -0.12065 -0.2794)
			(stroke
				(width 0.1)
				(type default)
			)
			(layer "F.Fab")
		)
		(pad "1" smd circle
			(at -0.40005 0 270)
			(size 0 0)
			(layers "F.Cu" "F.Mask" "F.Paste")
			(net "PVDD11_S3_P1")
		)
		(pad "2" smd circle
			(at 0.40005 0 270)
			(size 0 0)
			(layers "F.Cu" "F.Mask" "F.Paste")
			(net "I3C_SPD_DDRGL_CPU1_LVC1_SCL")
		)
	)
)
